(kicad_pcb
	(version 20260206)
	(generator "pcbnew")
	(generator_version "10.0")
	(general
		(thickness 1.6)
		(legacy_teardrops no)
	)
	(paper "A4")
	(title_block
		(title "Wiwynn_Tioga_Pass_MB.brd")
		(comment 1 "Tioga Pass / footprint 2254 of 4770 (U5D1), pads 1534-1644 of 3647")
	)
	(layers
		(0 "F.Cu" signal "TOP")
		(4 "In1.Cu" signal "L2GND")
		(6 "In2.Cu" signal "L3")
		(8 "In3.Cu" signal "L4GND")
		(10 "In4.Cu" signal "L5")
		(12 "In5.Cu" signal "L6GND")
		(14 "In6.Cu" signal "L7VCC")
		(16 "In7.Cu" signal "L8VCC")
		(18 "In8.Cu" signal "L9GND")
		(20 "In9.Cu" signal "L10")
		(22 "In10.Cu" signal "L11GND")
		(24 "In11.Cu" signal "L12")
		(26 "In12.Cu" signal "L13GND")
		(2 "B.Cu" signal "BOTTOM")
		(9 "F.Adhes" user "F.Adhesive")
		(11 "B.Adhes" user "B.Adhesive")
		(13 "F.Paste" user "Package Geometry/Pastemask Top")
		(15 "B.Paste" user "Package Geometry/Pastemask Bottom")
		(5 "F.SilkS" user "Ref Des/Silkscreen Top")
		(7 "B.SilkS" user "Ref Des/Silkscreen Bottom")
		(1 "F.Mask" user "Board Geometry/Soldermask Top")
		(3 "B.Mask" user "Board Geometry/Soldermask Bottom")
		(17 "Dwgs.User" user "User.Drawings")
		(19 "Cmts.User" user "User.Comments")
		(21 "Eco1.User" user "User.Eco1")
		(23 "Eco2.User" user "User.Eco2")
		(25 "Edge.Cuts" user "Board Geometry/Outline")
		(27 "Margin" user)
		(31 "F.CrtYd" user "Package Geometry/Place Bound Top")
		(29 "B.CrtYd" user "Package Geometry/Place Bound Bottom")
		(35 "F.Fab" user "Ref Des/Assembly Top")
		(33 "B.Fab" user "Ref Des/Assembly Bottom")
	)
	(footprint ""
		(layer "F.Cu")
		(at 270.000222 -76.550012 180)
		(property "Reference" "U5D1"
			(at 19.124422 31.601918 0)
			(unlocked yes)
			(layer "F.SilkS")
			(effects
				(font
					(size 0.7874 0.5842)
					(thickness 0.1524)
				)
			)
		)
		(property "Value" ""
			(at 0 0 180)
			(layer "F.Fab")
			(effects
				(font
					(size 1.27 1.27)
				)
			)
		)
		(duplicate_pad_numbers_are_jumpers no)
		(pad "CK1" smd custom
			(at -37.250624 9.072372 90)
			(size 0.10795 0.10795)
			(layers "F.Cu" "F.Mask" "F.Paste")
			(net "P3E_CPU0_PE2_SS_TXP<4>")
			(options
				(clearance outline)
				(anchor circle)
			)
			(primitives
				(gr_poly
					(pts
						(arc
							(start 0.2159 -0.0381)
							(mid 0 -0.254)
							(end -0.2159 -0.0381)
						)
						(arc
							(start -0.2159 0.0381)
							(mid 0 0.254)
							(end 0.2159 0.0381)
						)
					)
					(width 0)
					(fill yes)
				)
			)
		)
		(pad "CK3" smd circle
			(at -35.533584 9.072372)
			(size 0.4318 0.4318)
			(layers "F.Cu" "F.Mask" "F.Paste")
			(net "P3E_CPU0_PE2_SS_TXP<5>")
		)
		(pad "CK5" smd circle
			(at -33.816544 9.072372)
			(size 0.4318 0.4318)
			(layers "F.Cu" "F.Mask" "F.Paste")
			(net "PVCCIO_CPU0")
		)
		(pad "CK7" smd circle
			(at -32.099504 9.072372)
			(size 0.4318 0.4318)
			(layers "F.Cu" "F.Mask" "F.Paste")
			(net "P3E_CPU0_PE2_SS_RXN<4>")
		)
		(pad "CK9" smd circle
			(at -30.382464 9.072372)
			(size 0.4318 0.4318)
			(layers "F.Cu" "F.Mask" "F.Paste")
			(net "DMI_CPU0_PCH_RX_C_DN<0>")
		)
		(pad "CK11" smd circle
			(at -28.665424 9.072372)
			(size 0.4318 0.4318)
			(layers "F.Cu" "F.Mask" "F.Paste")
			(net "GND")
		)
		(pad "CK13" smd circle
			(at -26.948384 9.072372)
			(size 0.4318 0.4318)
			(layers "F.Cu" "F.Mask" "F.Paste")
			(net "TP_CPU0_UPI2_RSVD_DF17")
		)
		(pad "CK15" smd circle
			(at -25.231598 9.072372)
			(size 0.4318 0.4318)
			(layers "F.Cu" "F.Mask" "F.Paste")
			(net "GND")
		)
		(pad "CK17" smd circle
			(at -23.514558 9.072372)
			(size 0.4318 0.4318)
			(layers "F.Cu" "F.Mask" "F.Paste")
			(net "GND")
		)
		(pad "CK19" smd circle
			(at -21.797518 9.072372)
			(size 0.4318 0.4318)
			(layers "F.Cu" "F.Mask" "F.Paste")
			(net "TP_CPU0_RSVD_85")
		)
		(pad "CK21" smd circle
			(at -20.080478 9.072372)
			(size 0.4318 0.4318)
			(layers "F.Cu" "F.Mask" "F.Paste")
			(net "GND")
		)
		(pad "CK23" smd circle
			(at -18.363438 9.072372)
			(size 0.4318 0.4318)
			(layers "F.Cu" "F.Mask" "F.Paste")
			(net "PVCCMCP_CPU0")
		)
		(pad "CK25" smd circle
			(at -16.646398 9.072372)
			(size 0.4318 0.4318)
			(layers "F.Cu" "F.Mask" "F.Paste")
			(net "PVCCMCP_CPU0")
		)
		(pad "CK27" smd circle
			(at -14.929612 9.072372)
			(size 0.4318 0.4318)
			(layers "F.Cu" "F.Mask" "F.Paste")
			(net "GND")
		)
		(pad "CK29" smd circle
			(at -13.212572 9.072372)
			(size 0.4318 0.4318)
			(layers "F.Cu" "F.Mask" "F.Paste")
			(net "A_CPU0_UPI2_RBIAS")
		)
		(pad "CK59" smd circle
			(at 14.071092 7.272274)
			(size 0.508 0.508)
			(layers "F.Cu" "F.Mask" "F.Paste")
			(net "PVCCIN_CPU0")
		)
		(pad "CK61" smd circle
			(at 15.787878 7.272274)
			(size 0.4318 0.4318)
			(layers "F.Cu" "F.Mask" "F.Paste")
			(net "PVCCIN_CPU0")
		)
		(pad "CK63" smd circle
			(at 17.504918 7.272274)
			(size 0.4318 0.4318)
			(layers "F.Cu" "F.Mask" "F.Paste")
			(net "GND")
		)
		(pad "CK65" smd circle
			(at 19.221958 7.272274)
			(size 0.4318 0.4318)
			(layers "F.Cu" "F.Mask" "F.Paste")
			(net "GND")
		)
		(pad "CK67" smd circle
			(at 20.938998 7.272274)
			(size 0.4318 0.4318)
			(layers "F.Cu" "F.Mask" "F.Paste")
			(net "GND")
		)
		(pad "CK69" smd circle
			(at 22.656038 7.272274)
			(size 0.4318 0.4318)
			(layers "F.Cu" "F.Mask" "F.Paste")
			(net "GND")
		)
		(pad "CK71" smd circle
			(at 24.373078 7.272274)
			(size 0.4318 0.4318)
			(layers "F.Cu" "F.Mask" "F.Paste")
			(net "GND")
		)
		(pad "CK73" smd circle
			(at 26.090118 7.272274)
			(size 0.4318 0.4318)
			(layers "F.Cu" "F.Mask" "F.Paste")
			(net "GND")
		)
		(pad "CK75" smd circle
			(at 27.806904 7.272274)
			(size 0.4318 0.4318)
			(layers "F.Cu" "F.Mask" "F.Paste")
			(net "GND")
		)
		(pad "CK77" smd circle
			(at 29.523944 7.272274)
			(size 0.4318 0.4318)
			(layers "F.Cu" "F.Mask" "F.Paste")
			(net "TP_CPU0_RSVD_82")
		)
		(pad "CK79" smd circle
			(at 31.240984 7.272274)
			(size 0.4318 0.4318)
			(layers "F.Cu" "F.Mask" "F.Paste")
			(net "M_E_DQ<4>")
		)
		(pad "CK81" smd circle
			(at 32.958024 7.272274)
			(size 0.4318 0.4318)
			(layers "F.Cu" "F.Mask" "F.Paste")
			(net "M_E_DQ<1>")
		)
		(pad "CK83" smd circle
			(at 34.675064 7.272274)
			(size 0.4318 0.4318)
			(layers "F.Cu" "F.Mask" "F.Paste")
			(net "GND")
		)
		(pad "CK85" smd circle
			(at 36.392104 7.272274)
			(size 0.4318 0.4318)
			(layers "F.Cu" "F.Mask" "F.Paste")
			(net "GND")
		)
		(pad "CL2" smd circle
			(at -36.392104 9.567926)
			(size 0.4318 0.4318)
			(layers "F.Cu" "F.Mask" "F.Paste")
			(net "P3E_CPU0_PE2_SS_TXN<5>")
		)
		(pad "CL4" smd circle
			(at -34.675064 9.567926)
			(size 0.4318 0.4318)
			(layers "F.Cu" "F.Mask" "F.Paste")
			(net "DMI_CPU0_PCH_TX_DP<1>")
		)
		(pad "CL6" smd circle
			(at -32.958024 9.567926)
			(size 0.4318 0.4318)
			(layers "F.Cu" "F.Mask" "F.Paste")
			(net "P3E_CPU0_PE2_SS_RXP<3>")
		)
		(pad "CL8" smd circle
			(at -31.240984 9.567926)
			(size 0.4318 0.4318)
			(layers "F.Cu" "F.Mask" "F.Paste")
			(net "GND")
		)
		(pad "CL10" smd circle
			(at -29.523944 9.567926)
			(size 0.4318 0.4318)
			(layers "F.Cu" "F.Mask" "F.Paste")
			(net "DMI_CPU0_PCH_RX_C_DP<0>")
		)
		(pad "CL12" smd circle
			(at -27.806904 9.567926)
			(size 0.4318 0.4318)
			(layers "F.Cu" "F.Mask" "F.Paste")
			(net "PVCCIO_CPU0")
		)
		(pad "CL14" smd circle
			(at -26.090118 9.567926)
			(size 0.4318 0.4318)
			(layers "F.Cu" "F.Mask" "F.Paste")
			(net "GND")
		)
		(pad "CL16" smd circle
			(at -24.373078 9.567926)
			(size 0.4318 0.4318)
			(layers "F.Cu" "F.Mask" "F.Paste")
			(net "GND")
		)
		(pad "CL18" smd circle
			(at -22.656038 9.567926)
			(size 0.4318 0.4318)
			(layers "F.Cu" "F.Mask" "F.Paste")
			(net "GND")
		)
		(pad "CL20" smd circle
			(at -20.938998 9.567926)
			(size 0.4318 0.4318)
			(layers "F.Cu" "F.Mask" "F.Paste")
			(net "PVCCIO_CPU0")
		)
		(pad "CL22" smd circle
			(at -19.221958 9.567926)
			(size 0.4318 0.4318)
			(layers "F.Cu" "F.Mask" "F.Paste")
			(net "GND")
		)
		(pad "CL24" smd circle
			(at -17.504918 9.567926)
			(size 0.4318 0.4318)
			(layers "F.Cu" "F.Mask" "F.Paste")
			(net "PVCCMCP_CPU0")
		)
		(pad "CL26" smd circle
			(at -15.787878 9.567926)
			(size 0.4318 0.4318)
			(layers "F.Cu" "F.Mask" "F.Paste")
			(net "PVCCMCP_CPU0")
		)
		(pad "CL28" smd circle
			(at -14.071092 9.567926)
			(size 0.4318 0.4318)
			(layers "F.Cu" "F.Mask" "F.Paste")
			(net "A_CPU0_UPI2_RBIAS")
		)
		(pad "CL30" smd circle
			(at -12.354052 9.567926)
			(size 0.4318 0.4318)
			(layers "F.Cu" "F.Mask" "F.Paste")
			(net "A_CPU0_PE012_RBIAS")
		)
		(pad "CL58" smd circle
			(at 13.212572 7.767828)
			(size 0.508 0.508)
			(layers "F.Cu" "F.Mask" "F.Paste")
			(net "PVCCIN_CPU0")
		)
		(pad "CL60" smd circle
			(at 14.929612 7.767828)
			(size 0.4318 0.4318)
			(layers "F.Cu" "F.Mask" "F.Paste")
			(net "PVCCIN_CPU0")
		)
		(pad "CL62" smd circle
			(at 16.646398 7.767828)
			(size 0.4318 0.4318)
			(layers "F.Cu" "F.Mask" "F.Paste")
			(net "GND")
		)
		(pad "CL64" smd circle
			(at 18.363438 7.767828)
			(size 0.4318 0.4318)
			(layers "F.Cu" "F.Mask" "F.Paste")
			(net "GND")
		)
		(pad "CL66" smd circle
			(at 20.080478 7.767828)
			(size 0.4318 0.4318)
			(layers "F.Cu" "F.Mask" "F.Paste")
			(net "GND")
		)
		(pad "CL68" smd circle
			(at 21.797518 7.767828)
			(size 0.4318 0.4318)
			(layers "F.Cu" "F.Mask" "F.Paste")
			(net "M_F_ECC<3>")
		)
		(pad "CL70" smd circle
			(at 23.514558 7.767828)
			(size 0.4318 0.4318)
			(layers "F.Cu" "F.Mask" "F.Paste")
			(net "M_F_DQS_DP<8>")
		)
		(pad "CL72" smd circle
			(at 25.231598 7.767828)
			(size 0.4318 0.4318)
			(layers "F.Cu" "F.Mask" "F.Paste")
			(net "M_F_ECC<5>")
		)
		(pad "CL74" smd circle
			(at 26.948384 7.767828)
			(size 0.4318 0.4318)
			(layers "F.Cu" "F.Mask" "F.Paste")
			(net "GND")
		)
		(pad "CL76" smd circle
			(at 28.665424 7.767828)
			(size 0.4318 0.4318)
			(layers "F.Cu" "F.Mask" "F.Paste")
			(net "GND")
		)
		(pad "CL78" smd circle
			(at 30.382464 7.767828)
			(size 0.4318 0.4318)
			(layers "F.Cu" "F.Mask" "F.Paste")
			(net "GND")
		)
		(pad "CL80" smd circle
			(at 32.099504 7.767828)
			(size 0.4318 0.4318)
			(layers "F.Cu" "F.Mask" "F.Paste")
			(net "GND")
		)
		(pad "CL82" smd circle
			(at 33.816544 7.767828)
			(size 0.4318 0.4318)
			(layers "F.Cu" "F.Mask" "F.Paste")
			(net "M_E_DQS_DN<0>")
		)
		(pad "CL84" smd circle
			(at 35.533584 7.767828)
			(size 0.4318 0.4318)
			(layers "F.Cu" "F.Mask" "F.Paste")
			(net "M_D_DQ<4>")
		)
		(pad "CL86" smd custom
			(at 37.250624 7.767828 270)
			(size 0.10795 0.10795)
			(layers "F.Cu" "F.Mask" "F.Paste")
			(net "M_D_DQ<5>")
			(options
				(clearance outline)
				(anchor circle)
			)
			(primitives
				(gr_poly
					(pts
						(arc
							(start 0.2159 -0.0381)
							(mid 0 -0.254)
							(end -0.2159 -0.0381)
						)
						(arc
							(start -0.2159 0.0381)
							(mid 0 0.254)
							(end 0.2159 0.0381)
						)
					)
					(width 0)
					(fill yes)
				)
			)
		)
		(pad "CM1" smd custom
			(at -37.250624 10.062972 90)
			(size 0.10795 0.10795)
			(layers "F.Cu" "F.Mask" "F.Paste")
			(net "P3E_CPU0_PE2_SS_TXN<4>")
			(options
				(clearance outline)
				(anchor circle)
			)
			(primitives
				(gr_poly
					(pts
						(arc
							(start 0.2159 -0.0381)
							(mid 0 -0.254)
							(end -0.2159 -0.0381)
						)
						(arc
							(start -0.2159 0.0381)
							(mid 0 0.254)
							(end 0.2159 0.0381)
						)
					)
					(width 0)
					(fill yes)
				)
			)
		)
		(pad "CM3" smd circle
			(at -35.533584 10.062972)
			(size 0.4318 0.4318)
			(layers "F.Cu" "F.Mask" "F.Paste")
			(net "DMI_CPU0_PCH_TX_DP<2>")
		)
		(pad "CM5" smd circle
			(at -33.816544 10.062972)
			(size 0.4318 0.4318)
			(layers "F.Cu" "F.Mask" "F.Paste")
			(net "GND")
		)
		(pad "CM7" smd circle
			(at -32.099504 10.062972)
			(size 0.4318 0.4318)
			(layers "F.Cu" "F.Mask" "F.Paste")
			(net "P3E_CPU0_PE2_SS_RXN<3>")
		)
		(pad "CM9" smd circle
			(at -30.382464 10.062972)
			(size 0.4318 0.4318)
			(layers "F.Cu" "F.Mask" "F.Paste")
			(net "P3E_CPU0_PE2_SS_RXP<1>")
		)
		(pad "CM11" smd circle
			(at -28.665424 10.062972)
			(size 0.4318 0.4318)
			(layers "F.Cu" "F.Mask" "F.Paste")
			(net "DMI_CPU0_PCH_RX_C_DN<1>")
		)
		(pad "CM13" smd circle
			(at -26.948384 10.062972)
			(size 0.4318 0.4318)
			(layers "F.Cu" "F.Mask" "F.Paste")
			(net "TP_CPU0_UPI2_RSVD_DG18")
		)
		(pad "CM15" smd circle
			(at -25.231598 10.062972)
			(size 0.4318 0.4318)
			(layers "F.Cu" "F.Mask" "F.Paste")
			(net "PVCCIO_CPU0")
		)
		(pad "CM19" smd circle
			(at -21.797518 10.062972)
			(size 0.4318 0.4318)
			(layers "F.Cu" "F.Mask" "F.Paste")
			(net "GND")
		)
		(pad "CM21" smd circle
			(at -20.080478 10.062972)
			(size 0.4318 0.4318)
			(layers "F.Cu" "F.Mask" "F.Paste")
			(net "GND")
		)
		(pad "CM23" smd circle
			(at -18.363438 10.062972)
			(size 0.4318 0.4318)
			(layers "F.Cu" "F.Mask" "F.Paste")
			(net "PVCCMCP_CPU0")
		)
		(pad "CM25" smd circle
			(at -16.646398 10.062972)
			(size 0.4318 0.4318)
			(layers "F.Cu" "F.Mask" "F.Paste")
			(net "PVCCMCP_CPU0")
		)
		(pad "CM27" smd circle
			(at -14.929612 10.062972)
			(size 0.4318 0.4318)
			(layers "F.Cu" "F.Mask" "F.Paste")
			(net "GND")
		)
		(pad "CM29" smd circle
			(at -13.212572 10.062972)
			(size 0.4318 0.4318)
			(layers "F.Cu" "F.Mask" "F.Paste")
			(net "GND")
		)
		(pad "CM31" smd circle
			(at -11.495532 10.062972)
			(size 0.4318 0.4318)
			(layers "F.Cu" "F.Mask" "F.Paste")
			(net "GND")
		)
		(pad "CM57" smd circle
			(at 12.354052 8.262874)
			(size 0.508 0.508)
			(layers "F.Cu" "F.Mask" "F.Paste")
			(net "PVCCIN_CPU0")
		)
		(pad "CM59" smd circle
			(at 14.071092 8.262874)
			(size 0.4318 0.4318)
			(layers "F.Cu" "F.Mask" "F.Paste")
			(net "PVCCIN_CPU0")
		)
		(pad "CM61" smd circle
			(at 15.787878 8.262874)
			(size 0.4318 0.4318)
			(layers "F.Cu" "F.Mask" "F.Paste")
			(net "GND")
		)
		(pad "CM63" smd circle
			(at 17.504918 8.262874)
			(size 0.4318 0.4318)
			(layers "F.Cu" "F.Mask" "F.Paste")
			(net "GND")
		)
		(pad "CM65" smd circle
			(at 19.221958 8.262874)
			(size 0.4318 0.4318)
			(layers "F.Cu" "F.Mask" "F.Paste")
			(net "M_F_DQS_DP<12>")
		)
		(pad "CM67" smd circle
			(at 20.938998 8.262874)
			(size 0.4318 0.4318)
			(layers "F.Cu" "F.Mask" "F.Paste")
			(net "GND")
		)
		(pad "CM69" smd circle
			(at 22.656038 8.262874)
			(size 0.4318 0.4318)
			(layers "F.Cu" "F.Mask" "F.Paste")
			(net "M_F_ECC<7>")
		)
		(pad "CM71" smd circle
			(at 24.373078 8.262874)
			(size 0.4318 0.4318)
			(layers "F.Cu" "F.Mask" "F.Paste")
			(net "M_F_ECC<1>")
		)
		(pad "CM73" smd circle
			(at 26.090118 8.262874)
			(size 0.4318 0.4318)
			(layers "F.Cu" "F.Mask" "F.Paste")
			(net "GND")
		)
		(pad "CM75" smd circle
			(at 27.806904 8.262874)
			(size 0.4318 0.4318)
			(layers "F.Cu" "F.Mask" "F.Paste")
			(net "M_F_DQ<5>")
		)
		(pad "CM77" smd circle
			(at 29.523944 8.262874)
			(size 0.4318 0.4318)
			(layers "F.Cu" "F.Mask" "F.Paste")
			(net "GND")
		)
		(pad "CM79" smd circle
			(at 31.240984 8.262874)
			(size 0.4318 0.4318)
			(layers "F.Cu" "F.Mask" "F.Paste")
			(net "M_E_DQ<0>")
		)
		(pad "CM81" smd circle
			(at 32.958024 8.262874)
			(size 0.4318 0.4318)
			(layers "F.Cu" "F.Mask" "F.Paste")
			(net "M_E_DQS_DP<0>")
		)
		(pad "CM83" smd circle
			(at 34.675064 8.262874)
			(size 0.4318 0.4318)
			(layers "F.Cu" "F.Mask" "F.Paste")
			(net "GND")
		)
		(pad "CM85" smd circle
			(at 36.392104 8.262874)
			(size 0.4318 0.4318)
			(layers "F.Cu" "F.Mask" "F.Paste")
			(net "GND")
		)
		(pad "CN2" smd circle
			(at -36.392104 10.558526)
			(size 0.4318 0.4318)
			(layers "F.Cu" "F.Mask" "F.Paste")
			(net "GND")
		)
		(pad "CN4" smd circle
			(at -34.675064 10.558526)
			(size 0.4318 0.4318)
			(layers "F.Cu" "F.Mask" "F.Paste")
			(net "DMI_CPU0_PCH_TX_DN<2>")
		)
		(pad "CN6" smd circle
			(at -32.958024 10.558526)
			(size 0.4318 0.4318)
			(layers "F.Cu" "F.Mask" "F.Paste")
			(net "PVCCIO_CPU0")
		)
		(pad "CN8" smd circle
			(at -31.240984 10.558526)
			(size 0.4318 0.4318)
			(layers "F.Cu" "F.Mask" "F.Paste")
			(net "P3E_CPU0_PE2_SS_RXP<2>")
		)
		(pad "CN10" smd circle
			(at -29.523944 10.558526)
			(size 0.4318 0.4318)
			(layers "F.Cu" "F.Mask" "F.Paste")
			(net "DMI_CPU0_PCH_RX_C_DP<1>")
		)
		(pad "CN12" smd circle
			(at -27.806904 10.558526)
			(size 0.4318 0.4318)
			(layers "F.Cu" "F.Mask" "F.Paste")
			(net "GND")
		)
		(pad "CN14" smd circle
			(at -26.090118 10.558526)
			(size 0.4318 0.4318)
			(layers "F.Cu" "F.Mask" "F.Paste")
			(net "GND")
		)
		(pad "CN18" smd circle
			(at -22.656038 10.558526)
			(size 0.4318 0.4318)
			(layers "F.Cu" "F.Mask" "F.Paste")
			(net "GND")
		)
		(pad "CN20" smd circle
			(at -20.938998 10.558526)
			(size 0.4318 0.4318)
			(layers "F.Cu" "F.Mask" "F.Paste")
			(net "GND")
		)
		(pad "CN22" smd circle
			(at -19.221958 10.558526)
			(size 0.4318 0.4318)
			(layers "F.Cu" "F.Mask" "F.Paste")
			(net "TP_CPU0_KTI2_AMONV")
		)
		(pad "CN24" smd circle
			(at -17.504918 10.558526)
			(size 0.4318 0.4318)
			(layers "F.Cu" "F.Mask" "F.Paste")
			(net "PVCCMCP_CPU0")
		)
		(pad "CN26" smd circle
			(at -15.787878 10.558526)
			(size 0.4318 0.4318)
			(layers "F.Cu" "F.Mask" "F.Paste")
			(net "GND")
		)
		(pad "CN28" smd circle
			(at -14.071092 10.558526)
			(size 0.4318 0.4318)
			(layers "F.Cu" "F.Mask" "F.Paste")
			(net "PD_CPU0_MCP01_DMON")
		)
		(pad "CN30" smd circle
			(at -12.354052 10.558526)
			(size 0.4318 0.4318)
			(layers "F.Cu" "F.Mask" "F.Paste")
			(net "A_CPU0_PE012_RBIAS")
		)
		(pad "CN32" smd circle
			(at -10.637012 10.558526)
			(size 0.4318 0.4318)
			(layers "F.Cu" "F.Mask" "F.Paste")
			(net "GND")
		)
		(pad "CN56" smd circle
			(at 11.495532 8.758428)
			(size 0.508 0.508)
			(layers "F.Cu" "F.Mask" "F.Paste")
			(net "PVCCIN_CPU0")
		)
		(pad "CN58" smd circle
			(at 13.212572 8.758428)
			(size 0.4318 0.4318)
			(layers "F.Cu" "F.Mask" "F.Paste")
			(net "PVCCIN_CPU0")
		)
		(pad "CN60" smd circle
			(at 14.929612 8.758428)
			(size 0.4318 0.4318)
			(layers "F.Cu" "F.Mask" "F.Paste")
			(net "GND")
		)
		(pad "CN62" smd circle
			(at 16.646398 8.758428)
			(size 0.4318 0.4318)
			(layers "F.Cu" "F.Mask" "F.Paste")
			(net "GND")
		)
		(pad "CN64" smd circle
			(at 18.363438 8.758428)
			(size 0.4318 0.4318)
			(layers "F.Cu" "F.Mask" "F.Paste")
			(net "M_F_DQ<30>")
		)
		(pad "CN66" smd circle
			(at 20.080478 8.758428)
			(size 0.4318 0.4318)
			(layers "F.Cu" "F.Mask" "F.Paste")
			(net "M_F_DQ<24>")
		)
		(pad "CN68" smd circle
			(at 21.797518 8.758428)
			(size 0.4318 0.4318)
			(layers "F.Cu" "F.Mask" "F.Paste")
			(net "GND")
		)
	)
)
